# S9S_MB_2U (Grand Teton) — schematic netlist excerpt (pin names and nets, part order shuffled) for the footprints in the layout excerpt that follows; sources: Cadence DE-HDL packaged netlist, KiCad conversion of 03242023_DA0F0TMBIJ0_F0T_Motherboard_J_brd_V01_OCP.brd

R3336  Q_RES  0 5% CHIP  pkg 0402LF  page 212 : A = CLK_100M_BMC_RC_DN_R ; B = CLK_100M_BMC_RC_DN
C973  Q_CAP  10UF 6.3V 20% X6S  pkg C0402  page 74 : A = PVCCIN_CPU0 ; B = GND

(kicad_pcb
	(version 20260206)
	(generator "pcbnew")
	(generator_version "10.0")
	(general
		(thickness 1.6)
		(legacy_teardrops no)
	)
	(paper "A4")
	(title_block
		(title "03242023_DA0F0TMBIJ0_F0T_Motherboard_J_brd_V01_OCP.brd")
		(comment 1 "Grand Teton / footprints 1379-1380 of 6105")
	)
	(layers
		(0 "F.Cu" signal "TOP")
		(4 "In1.Cu" signal "GND")
		(6 "In2.Cu" signal "IN1")
		(8 "In3.Cu" signal "GND1")
		(10 "In4.Cu" signal "IN2")
		(12 "In5.Cu" signal "GND2")
		(14 "In6.Cu" signal "IN3")
		(16 "In7.Cu" signal "GND3")
		(18 "In8.Cu" signal "VCC")
		(20 "In9.Cu" signal "VCC1")
		(22 "In10.Cu" signal "GND4")
		(24 "In11.Cu" signal "IN4")
		(26 "In12.Cu" signal "GND5")
		(28 "In13.Cu" signal "IN5")
		(30 "In14.Cu" signal "GND6")
		(32 "In15.Cu" signal "IN6")
		(34 "In16.Cu" signal "GND7")
		(2 "B.Cu" signal "BOTTOM")
		(9 "F.Adhes" user "F.Adhesive")
		(11 "B.Adhes" user "B.Adhesive")
		(13 "F.Paste" user "Package Geometry/Pastemask Top")
		(15 "B.Paste" user "Package Geometry/Pastemask Bottom")
		(5 "F.SilkS" user "Ref Des/Silkscreen Top")
		(7 "B.SilkS" user "Ref Des/Silkscreen Bottom")
		(1 "F.Mask" user "Board Geometry/Soldermask Top")
		(3 "B.Mask" user "Board Geometry/Soldermask Bottom")
		(17 "Dwgs.User" user "User.Drawings")
		(19 "Cmts.User" user "User.Comments")
		(21 "Eco1.User" user "User.Eco1")
		(23 "Eco2.User" user "User.Eco2")
		(25 "Edge.Cuts" user "Board Geometry/Outline")
		(27 "Margin" user)
		(31 "F.CrtYd" user "Package Geometry/Place Bound Top")
		(29 "B.CrtYd" user "Package Geometry/Place Bound Bottom")
		(35 "F.Fab" user "Ref Des/Assembly Top")
		(33 "B.Fab" user "Ref Des/Assembly Bottom")
	)
	(footprint ""
		(layer "F.Cu")
		(at 230.248206 -251.189236 180)
		(property "Reference" "R3336"
			(at 0 0 180)
			(layer "F.SilkS")
			(hide yes)
			(effects
				(font
					(size 1.27 1.27)
				)
			)
		)
		(property "Value" ""
			(at 0 0 180)
			(layer "F.Fab")
			(effects
				(font
					(size 1.27 1.27)
				)
			)
		)
		(duplicate_pad_numbers_are_jumpers no)
		(fp_line
			(start 0.7874 0.4064)
			(end -0.7874 0.4064)
			(stroke
				(width 0.1524)
				(type default)
			)
			(layer "F.SilkS")
		)
		(fp_line
			(start 0.7874 -0.4064)
			(end 0.7874 0.4064)
			(stroke
				(width 0.1524)
				(type default)
			)
			(layer "F.SilkS")
		)
		(fp_line
			(start -0.7874 0.4064)
			(end -0.7874 -0.4064)
			(stroke
				(width 0.1524)
				(type default)
			)
			(layer "F.SilkS")
		)
		(fp_line
			(start -0.7874 -0.4064)
			(end 0.7874 -0.4064)
			(stroke
				(width 0.1524)
				(type default)
			)
			(layer "F.SilkS")
		)
		(fp_line
			(start 0.67945 0.3048)
			(end 0.120396 0.3048)
			(stroke
				(width 0.1)
				(type default)
			)
			(layer "F.Fab")
		)
		(fp_line
			(start 0.67945 -0.3048)
			(end 0.67945 0.3048)
			(stroke
				(width 0.1)
				(type default)
			)
			(layer "F.Fab")
		)
		(fp_line
			(start 0.12065 -0.2794)
			(end 0.12065 -0.3048)
			(stroke
				(width 0.1)
				(type default)
			)
			(layer "F.Fab")
		)
		(fp_line
			(start 0.12065 -0.3048)
			(end 0.67945 -0.3048)
			(stroke
				(width 0.1)
				(type default)
			)
			(layer "F.Fab")
		)
		(fp_line
			(start 0.120396 0.3048)
			(end 0.120396 0.2794)
			(stroke
				(width 0.1)
				(type default)
			)
			(layer "F.Fab")
		)
		(fp_line
			(start 0.120396 0.2794)
			(end -0.12065 0.2794)
			(stroke
				(width 0.1)
				(type default)
			)
			(layer "F.Fab")
		)
		(fp_line
			(start -0.12065 0.3048)
			(end -0.67945 0.3048)
			(stroke
				(width 0.1)
				(type default)
			)
			(layer "F.Fab")
		)
		(fp_line
			(start -0.12065 0.2794)
			(end -0.12065 0.3048)
			(stroke
				(width 0.1)
				(type default)
			)
			(layer "F.Fab")
		)
		(fp_line
			(start -0.12065 -0.2794)
			(end 0.12065 -0.2794)
			(stroke
				(width 0.1)
				(type default)
			)
			(layer "F.Fab")
		)
		(fp_line
			(start -0.12065 -0.305054)
			(end -0.12065 -0.2794)
			(stroke
				(width 0.1)
				(type default)
			)
			(layer "F.Fab")
		)
		(fp_line
			(start -0.67945 0.3048)
			(end -0.67945 -0.305054)
			(stroke
				(width 0.1)
				(type default)
			)
			(layer "F.Fab")
		)
		(fp_line
			(start -0.67945 -0.305054)
			(end -0.12065 -0.305054)
			(stroke
				(width 0.1)
				(type default)
			)
			(layer "F.Fab")
		)
		(pad "1" smd circle
			(at -0.40005 0 180)
			(size 0 0)
			(layers "F.Cu" "F.Mask" "F.Paste")
			(net "CLK_100M_BMC_RC_DN_R")
		)
		(pad "2" smd circle
			(at 0.40005 0 180)
			(size 0 0)
			(layers "F.Cu" "F.Mask" "F.Paste")
			(net "CLK_100M_BMC_RC_DN")
		)
	)
	(footprint ""
		(layer "F.Cu")
		(at 365.46663 -249.320304 -90)
		(property "Reference" "C973"
			(at 0 0 270)
			(layer "F.SilkS")
			(hide yes)
			(effects
				(font
					(size 1.27 1.27)
				)
			)
		)
		(property "Value" ""
			(at 0 0 270)
			(layer "F.Fab")
			(effects
				(font
					(size 1.27 1.27)
				)
			)
		)
		(duplicate_pad_numbers_are_jumpers no)
		(fp_line
			(start -0.7874 0.4064)
			(end -0.7874 -0.4064)
			(stroke
				(width 0.1524)
				(type default)
			)
			(layer "F.SilkS")
		)
		(fp_line
			(start 0.7874 0.4064)
			(end -0.7874 0.4064)
			(stroke
				(width 0.1524)
				(type default)
			)
			(layer "F.SilkS")
		)
		(fp_line
			(start -0.7874 -0.4064)
			(end 0.7874 -0.4064)
			(stroke
				(width 0.1524)
				(type default)
			)
			(layer "F.SilkS")
		)
		(fp_line
			(start 0.7874 -0.4064)
			(end 0.7874 0.4064)
			(stroke
				(width 0.1524)
				(type default)
			)
			(layer "F.SilkS")
		)
		(fp_line
			(start -0.67945 0.3048)
			(end -0.67945 -0.305054)
			(stroke
				(width 0.1)
				(type default)
			)
			(layer "F.Fab")
		)
		(fp_line
			(start -0.12065 0.3048)
			(end -0.67945 0.3048)
			(stroke
				(width 0.1)
				(type default)
			)
			(layer "F.Fab")
		)
		(fp_line
			(start 0.120396 0.3048)
			(end 0.120396 0.2794)
			(stroke
				(width 0.1)
				(type default)
			)
			(layer "F.Fab")
		)
		(fp_line
			(start 0.67945 0.3048)
			(end 0.120396 0.3048)
			(stroke
				(width 0.1)
				(type default)
			)
			(layer "F.Fab")
		)
		(fp_line
			(start -0.12065 0.2794)
			(end -0.12065 0.3048)
			(stroke
				(width 0.1)
				(type default)
			)
			(layer "F.Fab")
		)
		(fp_line
			(start 0.120396 0.2794)
			(end -0.12065 0.2794)
			(stroke
				(width 0.1)
				(type default)
			)
			(layer "F.Fab")
		)
		(fp_line
			(start -0.12065 -0.2794)
			(end 0.12065 -0.2794)
			(stroke
				(width 0.1)
				(type default)
			)
			(layer "F.Fab")
		)
		(fp_line
			(start 0.12065 -0.2794)
			(end 0.12065 -0.3048)
			(stroke
				(width 0.1)
				(type default)
			)
			(layer "F.Fab")
		)
		(fp_line
			(start 0.12065 -0.3048)
			(end 0.67945 -0.3048)
			(stroke
				(width 0.1)
				(type default)
			)
			(layer "F.Fab")
		)
		(fp_line
			(start 0.67945 -0.3048)
			(end 0.67945 0.3048)
			(stroke
				(width 0.1)
				(type default)
			)
			(layer "F.Fab")
		)
		(fp_line
			(start -0.67945 -0.305054)
			(end -0.12065 -0.305054)
			(stroke
				(width 0.1)
				(type default)
			)
			(layer "F.Fab")
		)
		(fp_line
			(start -0.12065 -0.305054)
			(end -0.12065 -0.2794)
			(stroke
				(width 0.1)
				(type default)
			)
			(layer "F.Fab")
		)
		(pad "1" smd circle
			(at -0.40005 0 270)
			(size 0 0)
			(layers "F.Cu" "F.Mask" "F.Paste")
			(net "PVCCIN_CPU0")
		)
		(pad "2" smd circle
			(at 0.40005 0 270)
			(size 0 0)
			(layers "F.Cu" "F.Mask" "F.Paste")
			(net "GND")
		)
	)
)
